(kicad_pcb
	(version 20260206)
	(generator "pcbnew")
	(generator_version "10.0")
	(general
		(thickness 1.6)
		(legacy_teardrops no)
	)
	(paper "A4")
	(title_block
		(title "baseboard — 13948-1b.1110WZS1818.brd")
		(comment 1 "Honey Badger (Wiwynn) / footprints 860-865 of 2523")
	)
	(layers
		(0 "F.Cu" signal "TOP")
		(4 "In1.Cu" signal "L2GND")
		(6 "In2.Cu" signal "L3")
		(8 "In3.Cu" signal "L4VCC")
		(10 "In4.Cu" signal "L5VCC")
		(12 "In5.Cu" signal "L6")
		(14 "In6.Cu" signal "L7GND")
		(2 "B.Cu" signal "BOTTOM")
		(9 "F.Adhes" user "F.Adhesive")
		(11 "B.Adhes" user "B.Adhesive")
		(13 "F.Paste" user "Package Geometry/Pastemask Top")
		(15 "B.Paste" user "Package Geometry/Pastemask Bottom")
		(5 "F.SilkS" user "Ref Des/Silkscreen Top")
		(7 "B.SilkS" user "Ref Des/Silkscreen Bottom")
		(1 "F.Mask" user "Board Geometry/Soldermask Top")
		(3 "B.Mask" user "Board Geometry/Soldermask Bottom")
		(17 "Dwgs.User" user "User.Drawings")
		(19 "Cmts.User" user "User.Comments")
		(21 "Eco1.User" user "User.Eco1")
		(23 "Eco2.User" user "User.Eco2")
		(25 "Edge.Cuts" user "Board Geometry/Outline")
		(27 "Margin" user)
		(31 "F.CrtYd" user "Package Geometry/Place Bound Top")
		(29 "B.CrtYd" user "Package Geometry/Place Bound Bottom")
		(35 "F.Fab" user "Ref Des/Assembly Top")
		(33 "B.Fab" user "Ref Des/Assembly Bottom")
	)
	(footprint ""
		(layer "F.Cu")
		(at 266.065 -178.054 90)
		(property "Reference" "R345"
			(at 0 0 90)
			(layer "F.SilkS")
			(hide yes)
			(effects
				(font
					(size 1.27 1.27)
				)
			)
		)
		(property "Value" "3K3R2F-2-GP"
			(at 0.064008 -3.993896 90)
			(unlocked yes)
			(layer "F.Fab")
			(hide yes)
			(effects
				(font
					(size 1.016 1.016)
					(thickness 0.1524)
				)
			)
		)
		(property "Device Type" "R402H16"
			(at 0.064008 -5.517896 90)
			(unlocked yes)
			(layer "F.Fab")
			(hide yes)
			(effects
				(font
					(size 1.016 1.016)
					(thickness 0.1524)
				)
			)
		)
		(duplicate_pad_numbers_are_jumpers no)
		(fp_line
			(start 0.508 -0.9398)
			(end -0.508 -0.9398)
			(stroke
				(width 0.1524)
				(type default)
			)
			(layer "F.SilkS")
		)
		(fp_line
			(start -0.508 -0.9398)
			(end -0.508 0.9398)
			(stroke
				(width 0.1524)
				(type default)
			)
			(layer "F.SilkS")
		)
		(fp_rect
			(start -0.508 0.9398)
			(end 0.508 -0.9398)
			(stroke
				(width 0)
				(type default)
			)
			(fill no)
			(layer "F.CrtYd")
		)
		(fp_rect
			(start -0.508 0.9398)
			(end 0.508 -0.9398)
			(stroke
				(width 0)
				(type default)
			)
			(fill no)
			(layer "F.Fab")
		)
		(pad "1" smd custom
			(at 0 -0.4445 90)
			(size 0.1397 0.1397)
			(layers "F.Cu" "F.Mask" "F.Paste")
			(net "P3V3_STBY")
			(options
				(clearance outline)
				(anchor circle)
			)
			(primitives
				(gr_poly
					(pts
						(arc
							(start -0.1778 -0.2794)
							(mid -0.249642 -0.249642)
							(end -0.2794 -0.1778)
						)
						(arc
							(start -0.2794 0.1778)
							(mid -0.249642 0.249642)
							(end -0.1778 0.2794)
						)
						(arc
							(start 0.1778 0.2794)
							(mid 0.249642 0.249642)
							(end 0.2794 0.1778)
						)
						(arc
							(start 0.2794 -0.1778)
							(mid 0.249642 -0.249642)
							(end 0.1778 -0.2794)
						)
					)
					(width 0)
					(fill yes)
				)
			)
		)
		(pad "2" smd custom
			(at 0 0.4445 90)
			(size 0.1397 0.1397)
			(layers "F.Cu" "F.Mask" "F.Paste")
			(net "ROMA17")
			(options
				(clearance outline)
				(anchor circle)
			)
			(primitives
				(gr_poly
					(pts
						(arc
							(start -0.1778 -0.2794)
							(mid -0.249642 -0.249642)
							(end -0.2794 -0.1778)
						)
						(arc
							(start -0.2794 0.1778)
							(mid -0.249642 0.249642)
							(end -0.1778 0.2794)
						)
						(arc
							(start 0.1778 0.2794)
							(mid 0.249642 0.249642)
							(end 0.2794 0.1778)
						)
						(arc
							(start 0.2794 -0.1778)
							(mid 0.249642 -0.249642)
							(end 0.1778 -0.2794)
						)
					)
					(width 0)
					(fill yes)
				)
			)
		)
	)
	(footprint ""
		(layer "F.Cu")
		(at 338.357718 -157.584648)
		(property "Reference" "R222"
			(at 0 0 0)
			(layer "F.SilkS")
			(hide yes)
			(effects
				(font
					(size 1.27 1.27)
				)
			)
		)
		(property "Value" "4K7R2F-GP"
			(at 0.064008 -3.993896 0)
			(unlocked yes)
			(layer "F.Fab")
			(hide yes)
			(effects
				(font
					(size 1.016 1.016)
					(thickness 0.1524)
				)
			)
		)
		(property "Device Type" "R402H16"
			(at 0.064008 -5.517896 0)
			(unlocked yes)
			(layer "F.Fab")
			(hide yes)
			(effects
				(font
					(size 1.016 1.016)
					(thickness 0.1524)
				)
			)
		)
		(duplicate_pad_numbers_are_jumpers no)
		(fp_line
			(start -0.508 -0.9398)
			(end -0.508 0.9398)
			(stroke
				(width 0.1524)
				(type default)
			)
			(layer "F.SilkS")
		)
		(fp_line
			(start 0.508 -0.9398)
			(end -0.508 -0.9398)
			(stroke
				(width 0.1524)
				(type default)
			)
			(layer "F.SilkS")
		)
		(fp_rect
			(start -0.508 0.9398)
			(end 0.508 -0.9398)
			(stroke
				(width 0)
				(type default)
			)
			(fill no)
			(layer "F.CrtYd")
		)
		(fp_rect
			(start -0.508 0.9398)
			(end 0.508 -0.9398)
			(stroke
				(width 0)
				(type default)
			)
			(fill no)
			(layer "F.Fab")
		)
		(pad "1" smd custom
			(at 0 -0.4445)
			(size 0.1397 0.1397)
			(layers "F.Cu" "F.Mask" "F.Paste")
			(net "P3V3_STBY")
			(options
				(clearance outline)
				(anchor circle)
			)
			(primitives
				(gr_poly
					(pts
						(arc
							(start -0.1778 -0.2794)
							(mid -0.249642 -0.249642)
							(end -0.2794 -0.1778)
						)
						(arc
							(start -0.2794 0.1778)
							(mid -0.249642 0.249642)
							(end -0.1778 0.2794)
						)
						(arc
							(start 0.1778 0.2794)
							(mid 0.249642 0.249642)
							(end 0.2794 0.1778)
						)
						(arc
							(start 0.2794 -0.1778)
							(mid 0.249642 -0.249642)
							(end 0.1778 -0.2794)
						)
					)
					(width 0)
					(fill yes)
				)
			)
		)
		(pad "2" smd custom
			(at 0 0.4445)
			(size 0.1397 0.1397)
			(layers "F.Cu" "F.Mask" "F.Paste")
			(net "USB_OCS_N2")
			(options
				(clearance outline)
				(anchor circle)
			)
			(primitives
				(gr_poly
					(pts
						(arc
							(start -0.1778 -0.2794)
							(mid -0.249642 -0.249642)
							(end -0.2794 -0.1778)
						)
						(arc
							(start -0.2794 0.1778)
							(mid -0.249642 0.249642)
							(end -0.1778 0.2794)
						)
						(arc
							(start 0.1778 0.2794)
							(mid 0.249642 0.249642)
							(end 0.2794 0.1778)
						)
						(arc
							(start 0.2794 -0.1778)
							(mid 0.249642 -0.249642)
							(end 0.1778 -0.2794)
						)
					)
					(width 0)
					(fill yes)
				)
			)
		)
	)
	(footprint ""
		(layer "F.Cu")
		(at 257.483864 -229.226872 90)
		(property "Reference" "R457"
			(at 0 0 90)
			(layer "F.SilkS")
			(hide yes)
			(effects
				(font
					(size 1.27 1.27)
				)
			)
		)
		(property "Value" "4K75R2F-1-GP"
			(at 0.064008 -3.993896 90)
			(unlocked yes)
			(layer "F.Fab")
			(hide yes)
			(effects
				(font
					(size 1.016 1.016)
					(thickness 0.1524)
				)
			)
		)
		(property "Device Type" "R402H16"
			(at 0.064008 -5.517896 90)
			(unlocked yes)
			(layer "F.Fab")
			(hide yes)
			(effects
				(font
					(size 1.016 1.016)
					(thickness 0.1524)
				)
			)
		)
		(duplicate_pad_numbers_are_jumpers no)
		(fp_line
			(start 0.508 -0.9398)
			(end -0.508 -0.9398)
			(stroke
				(width 0.1524)
				(type default)
			)
			(layer "F.SilkS")
		)
		(fp_line
			(start -0.508 -0.9398)
			(end -0.508 0.9398)
			(stroke
				(width 0.1524)
				(type default)
			)
			(layer "F.SilkS")
		)
		(fp_rect
			(start -0.508 0.9398)
			(end 0.508 -0.9398)
			(stroke
				(width 0)
				(type default)
			)
			(fill no)
			(layer "F.CrtYd")
		)
		(fp_rect
			(start -0.508 0.9398)
			(end 0.508 -0.9398)
			(stroke
				(width 0)
				(type default)
			)
			(fill no)
			(layer "F.Fab")
		)
		(pad "1" smd custom
			(at 0 -0.4445 90)
			(size 0.1397 0.1397)
			(layers "F.Cu" "F.Mask" "F.Paste")
			(net "P3V3_STBY")
			(options
				(clearance outline)
				(anchor circle)
			)
			(primitives
				(gr_poly
					(pts
						(arc
							(start -0.1778 -0.2794)
							(mid -0.249642 -0.249642)
							(end -0.2794 -0.1778)
						)
						(arc
							(start -0.2794 0.1778)
							(mid -0.249642 0.249642)
							(end -0.1778 0.2794)
						)
						(arc
							(start 0.1778 0.2794)
							(mid 0.249642 0.249642)
							(end 0.2794 0.1778)
						)
						(arc
							(start 0.2794 -0.1778)
							(mid 0.249642 -0.249642)
							(end 0.1778 -0.2794)
						)
					)
					(width 0)
					(fill yes)
				)
			)
		)
		(pad "2" smd custom
			(at 0 0.4445 90)
			(size 0.1397 0.1397)
			(layers "F.Cu" "F.Mask" "F.Paste")
			(net "TPS74801_1V26_STBY_EN")
			(options
				(clearance outline)
				(anchor circle)
			)
			(primitives
				(gr_poly
					(pts
						(arc
							(start -0.1778 -0.2794)
							(mid -0.249642 -0.249642)
							(end -0.2794 -0.1778)
						)
						(arc
							(start -0.2794 0.1778)
							(mid -0.249642 0.249642)
							(end -0.1778 0.2794)
						)
						(arc
							(start 0.1778 0.2794)
							(mid 0.249642 0.249642)
							(end 0.2794 0.1778)
						)
						(arc
							(start 0.2794 -0.1778)
							(mid 0.249642 -0.249642)
							(end 0.1778 -0.2794)
						)
					)
					(width 0)
					(fill yes)
				)
			)
		)
	)
	(footprint ""
		(layer "F.Cu")
		(at 323.85 -171.323 90)
		(property "Reference" "R412"
			(at 0 0 90)
			(layer "F.SilkS")
			(hide yes)
			(effects
				(font
					(size 1.27 1.27)
				)
			)
		)
		(property "Value" "0R2J-2-GP"
			(at 0.064008 -3.993896 90)
			(unlocked yes)
			(layer "F.Fab")
			(hide yes)
			(effects
				(font
					(size 1.016 1.016)
					(thickness 0.1524)
				)
			)
		)
		(property "Device Type" "R402H16"
			(at 0.064008 -5.517896 90)
			(unlocked yes)
			(layer "F.Fab")
			(hide yes)
			(effects
				(font
					(size 1.016 1.016)
					(thickness 0.1524)
				)
			)
		)
		(duplicate_pad_numbers_are_jumpers no)
		(fp_line
			(start 0.508 -0.9398)
			(end -0.508 -0.9398)
			(stroke
				(width 0.1524)
				(type default)
			)
			(layer "F.SilkS")
		)
		(fp_line
			(start -0.508 -0.9398)
			(end -0.508 0.9398)
			(stroke
				(width 0.1524)
				(type default)
			)
			(layer "F.SilkS")
		)
		(fp_rect
			(start -0.508 0.9398)
			(end 0.508 -0.9398)
			(stroke
				(width 0)
				(type default)
			)
			(fill no)
			(layer "F.CrtYd")
		)
		(fp_rect
			(start -0.508 0.9398)
			(end 0.508 -0.9398)
			(stroke
				(width 0)
				(type default)
			)
			(fill no)
			(layer "F.Fab")
		)
		(pad "1" smd custom
			(at 0 -0.4445 90)
			(size 0.1397 0.1397)
			(layers "F.Cu" "F.Mask" "F.Paste")
			(net "EXP_SMART_RX")
			(options
				(clearance outline)
				(anchor circle)
			)
			(primitives
				(gr_poly
					(pts
						(arc
							(start -0.1778 -0.2794)
							(mid -0.249642 -0.249642)
							(end -0.2794 -0.1778)
						)
						(arc
							(start -0.2794 0.1778)
							(mid -0.249642 0.249642)
							(end -0.1778 0.2794)
						)
						(arc
							(start 0.1778 0.2794)
							(mid 0.249642 0.249642)
							(end 0.2794 0.1778)
						)
						(arc
							(start 0.2794 -0.1778)
							(mid 0.249642 -0.249642)
							(end 0.1778 -0.2794)
						)
					)
					(width 0)
					(fill yes)
				)
			)
		)
		(pad "2" smd custom
			(at 0 0.4445 90)
			(size 0.1397 0.1397)
			(layers "F.Cu" "F.Mask" "F.Paste")
			(net "EXP_UART_RX_R")
			(options
				(clearance outline)
				(anchor circle)
			)
			(primitives
				(gr_poly
					(pts
						(arc
							(start -0.1778 -0.2794)
							(mid -0.249642 -0.249642)
							(end -0.2794 -0.1778)
						)
						(arc
							(start -0.2794 0.1778)
							(mid -0.249642 0.249642)
							(end -0.1778 0.2794)
						)
						(arc
							(start 0.1778 0.2794)
							(mid 0.249642 0.249642)
							(end 0.2794 0.1778)
						)
						(arc
							(start 0.2794 -0.1778)
							(mid 0.249642 -0.249642)
							(end 0.1778 -0.2794)
						)
					)
					(width 0)
					(fill yes)
				)
			)
		)
	)
	(footprint ""
		(layer "F.Cu")
		(at 326.600058 -1.800098)
		(property "Reference" "SW20"
			(at 0 0 0)
			(layer "F.SilkS")
			(hide yes)
			(effects
				(font
					(size 1.27 1.27)
				)
			)
		)
		(property "Value" "SW-SLIDE74-GP"
			(at -4.272534 -5.45465 0)
			(unlocked yes)
			(layer "F.Fab")
			(hide yes)
			(effects
				(font
					(size 1.016 1.016)
					(thickness 0.1524)
				)
			)
		)
		(property "Device Type" "LSSM12-P-V-TR"
			(at -4.272534 -6.97865 0)
			(unlocked yes)
			(layer "F.Fab")
			(hide yes)
			(effects
				(font
					(size 1.016 1.016)
					(thickness 0.1524)
				)
			)
		)
		(duplicate_pad_numbers_are_jumpers no)
		(fp_line
			(start -5.0038 -2.0066)
			(end -3.3528 -2.0066)
			(stroke
				(width 0.1524)
				(type default)
			)
			(layer "F.SilkS")
		)
		(fp_line
			(start -5.0038 2.2098)
			(end -5.0038 -2.0066)
			(stroke
				(width 0.1524)
				(type default)
			)
			(layer "F.SilkS")
		)
		(fp_line
			(start -3.3528 -4.2418)
			(end 3.3528 -4.2418)
			(stroke
				(width 0.1524)
				(type default)
			)
			(layer "F.SilkS")
		)
		(fp_line
			(start -3.3528 -2.0066)
			(end -3.3528 -4.2418)
			(stroke
				(width 0.1524)
				(type default)
			)
			(layer "F.SilkS")
		)
		(fp_line
			(start -2.2987 -4.3688)
			(end -2.6797 -4.3688)
			(stroke
				(width 0.3302)
				(type default)
			)
			(layer "F.SilkS")
		)
		(fp_line
			(start -2.0066 2.2098)
			(end -5.0038 2.2098)
			(stroke
				(width 0.1524)
				(type default)
			)
			(layer "F.SilkS")
		)
		(fp_line
			(start -2.0066 4.0132)
			(end -2.0066 2.2098)
			(stroke
				(width 0.1524)
				(type default)
			)
			(layer "F.SilkS")
		)
		(fp_line
			(start 2.0066 2.2098)
			(end 2.0066 4.0132)
			(stroke
				(width 0.1524)
				(type default)
			)
			(layer "F.SilkS")
		)
		(fp_line
			(start 2.0066 4.0132)
			(end -2.0066 4.0132)
			(stroke
				(width 0.1524)
				(type default)
			)
			(layer "F.SilkS")
		)
		(fp_line
			(start 3.3528 -4.2418)
			(end 3.3528 -2.0066)
			(stroke
				(width 0.1524)
				(type default)
			)
			(layer "F.SilkS")
		)
		(fp_line
			(start 3.3528 -2.0066)
			(end 5.0038 -2.0066)
			(stroke
				(width 0.1524)
				(type default)
			)
			(layer "F.SilkS")
		)
		(fp_line
			(start 5.0038 -2.0066)
			(end 5.0038 2.2098)
			(stroke
				(width 0.1524)
				(type default)
			)
			(layer "F.SilkS")
		)
		(fp_line
			(start 5.0038 2.2098)
			(end 2.0066 2.2098)
			(stroke
				(width 0.1524)
				(type default)
			)
			(layer "F.SilkS")
		)
		(fp_poly
			(pts
				(xy -2.500122 -4.318) (xy -3.008122 -4.826) (xy -1.992122 -4.826)
			)
			(stroke
				(width 0)
				(type default)
			)
			(fill yes)
			(layer "F.SilkS")
		)
		(fp_poly
			(pts
				(xy -1.7526 3.7592) (xy -1.7526 1.9558) (xy -4.7498 1.9558) (xy -4.7498 -1.7526) (xy -2.794 -1.7526)
				(xy -2.794 -3.7592) (xy 2.794 -3.7592) (xy 2.794 -1.7526) (xy 4.7498 -1.7526) (xy 4.7498 1.9558)
				(xy 1.7526 1.9558) (xy 1.7526 3.7592)
			)
			(stroke
				(width 0)
				(type default)
			)
			(fill no)
			(layer "F.CrtYd")
		)
		(fp_poly
			(pts
				(xy -2.2606 4.2672) (xy -2.2606 2.4638) (xy -5.2578 2.4638) (xy -5.2578 -0.1524) (xy -4.7498 -0.1524)
				(xy -4.7498 1.9558) (xy -1.7526 1.9558) (xy -1.7526 3.7592) (xy 1.7526 3.7592) (xy 1.7526 1.9558)
				(xy 4.7498 1.9558) (xy 4.7498 -1.7526) (xy 2.794 -1.7526) (xy 2.794 -3.7592) (xy -2.794 -3.7592)
				(xy -2.794 -1.7526) (xy -4.7498 -1.7526) (xy -4.7498 -0.15748) (xy -5.2578 -0.15748) (xy -5.2578 -2.2606)
				(xy -3.6068 -2.2606) (xy -3.6068 -4.4958) (xy 3.6068 -4.4958) (xy 3.6068 -2.2606) (xy 5.2578 -2.2606)
				(xy 5.2578 2.4638) (xy 2.2606 2.4638) (xy 2.2606 4.2672)
			)
			(stroke
				(width 0)
				(type default)
			)
			(fill no)
			(layer "F.CrtYd")
		)
		(fp_poly
			(pts
				(xy -2.2606 4.2672) (xy -2.2606 2.4638) (xy -5.2578 2.4638) (xy -5.2578 -2.2606) (xy -3.6068 -2.2606)
				(xy -3.6068 -4.4958) (xy 3.6068 -4.4958) (xy 3.6068 -2.2606) (xy 5.2578 -2.2606) (xy 5.2578 2.4638)
				(xy 2.2606 2.4638) (xy 2.2606 4.2672)
			)
			(stroke
				(width 0)
				(type default)
			)
			(fill no)
			(layer "F.Fab")
		)
		(pad "" np_thru_hole circle
			(at -3.400044 0)
			(size 0.254 0.254)
			(drill 0.9652)
			(layers "*.Cu" "*.Mask")
			(clearance 0.7112)
			(thermal_gap 0.7112)
		)
		(pad "" np_thru_hole circle
			(at 3.400044 0)
			(size 0.254 0.254)
			(drill 0.9652)
			(layers "*.Cu" "*.Mask")
			(clearance 0.7112)
			(thermal_gap 0.7112)
		)
		(pad "1" smd rect
			(at -2.500122 -2.750058)
			(size 1.1938 2.4892)
			(layers "F.Cu" "F.Mask" "F.Paste")
			(net "DEBUG_LED_SW_H")
		)
		(pad "2" smd rect
			(at 0 -2.750058)
			(size 1.1938 2.4892)
			(layers "F.Cu" "F.Mask" "F.Paste")
			(net "DEBUG_LED_SW")
		)
		(pad "3" smd rect
			(at 2.500122 -2.750058)
			(size 1.1938 2.4892)
			(layers "F.Cu" "F.Mask" "F.Paste")
			(net "DEBUG_PORT_GND")
		)
		(zone
			(layers "F.Cu" "B.Cu" "In1.Cu" "In2.Cu" "In3.Cu" "In4.Cu" "In5.Cu" "In6.Cu")
			(hatch none 0.5)
			(connect_pads
				(clearance 0)
			)
			(min_thickness 0.25)
			(keepout
				(tracks not_allowed)
				(vias allowed)
				(pads allowed)
				(copperpour not_allowed)
				(footprints allowed)
			)
			(placement
				(enabled no)
				(sheetname "")
			)
			(fill
				(thermal_gap 0.5)
				(thermal_bridge_width 0.5)
				(island_removal_mode 0)
			)
			(polygon
				(pts
					(arc
						(start 323.987414 -1.800098)
						(mid 322.412614 -1.800098)
						(end 323.987414 -1.800098)
					)
				)
			)
		)
		(zone
			(layers "F.Cu" "B.Cu" "In1.Cu" "In2.Cu" "In3.Cu" "In4.Cu" "In5.Cu" "In6.Cu")
			(hatch none 0.5)
			(connect_pads
				(clearance 0)
			)
			(min_thickness 0.25)
			(keepout
				(tracks not_allowed)
				(vias allowed)
				(pads allowed)
				(copperpour not_allowed)
				(footprints allowed)
			)
			(placement
				(enabled no)
				(sheetname "")
			)
			(fill
				(thermal_gap 0.5)
				(thermal_bridge_width 0.5)
				(island_removal_mode 0)
			)
			(polygon
				(pts
					(arc
						(start 330.787502 -1.800098)
						(mid 329.212702 -1.800098)
						(end 330.787502 -1.800098)
					)
				)
			)
		)
	)
	(footprint ""
		(layer "F.Cu")
		(at 78.867 -4.572 180)
		(property "Reference" "PL10"
			(at 0 0 180)
			(layer "F.SilkS")
			(hide yes)
			(effects
				(font
					(size 1.27 1.27)
				)
			)
		)
		(property "Value" "BLM41PG600-GP"
			(at -3.690874 -7.441184 180)
			(unlocked yes)
			(layer "F.Fab")
			(hide yes)
			(effects
				(font
					(size 1.016 1.016)
					(thickness 0.1524)
				)
			)
		)
		(property "Device Type" "L451616H71"
			(at -3.690874 -5.917184 180)
			(unlocked yes)
			(layer "F.Fab")
			(hide yes)
			(effects
				(font
					(size 1.016 1.016)
					(thickness 0.1524)
				)
			)
		)
		(duplicate_pad_numbers_are_jumpers no)
		(fp_line
			(start 2.8702 1.2954)
			(end 2.8702 -1.2954)
			(stroke
				(width 0.1524)
				(type default)
			)
			(layer "F.SilkS")
		)
		(fp_line
			(start 2.8702 1.2954)
			(end 2.8702 -1.2954)
			(stroke
				(width 0.1524)
				(type default)
			)
			(layer "F.SilkS")
		)
		(fp_line
			(start 2.8702 -1.2954)
			(end -2.8702 -1.2954)
			(stroke
				(width 0.1524)
				(type default)
			)
			(layer "F.SilkS")
		)
		(fp_line
			(start 2.8702 -1.2954)
			(end -2.8702 -1.2954)
			(stroke
				(width 0.1524)
				(type default)
			)
			(layer "F.SilkS")
		)
		(fp_line
			(start -2.8702 1.2954)
			(end 2.8702 1.2954)
			(stroke
				(width 0.1524)
				(type default)
			)
			(layer "F.SilkS")
		)
		(fp_line
			(start -2.8702 1.2954)
			(end 2.8702 1.2954)
			(stroke
				(width 0.1524)
				(type default)
			)
			(layer "F.SilkS")
		)
		(fp_line
			(start -2.8702 -1.2954)
			(end -2.8702 1.2954)
			(stroke
				(width 0.1524)
				(type default)
			)
			(layer "F.SilkS")
		)
		(fp_line
			(start -2.8702 -1.2954)
			(end -2.8702 1.2954)
			(stroke
				(width 0.1524)
				(type default)
			)
			(layer "F.SilkS")
		)
		(fp_poly
			(pts
				(xy -2.8702 1.2954) (xy 2.8702 1.2954) (xy 2.8702 -1.2954) (xy -2.8702 -1.2954)
			)
			(stroke
				(width 0)
				(type default)
			)
			(fill no)
			(layer "F.CrtYd")
		)
		(fp_poly
			(pts
				(xy -2.8702 1.2954) (xy 2.8702 1.2954) (xy 2.8702 -1.2954) (xy -2.8702 -1.2954)
			)
			(stroke
				(width 0)
				(type default)
			)
			(fill no)
			(layer "F.Fab")
		)
		(pad "1" smd rect
			(at -1.9685 0 180)
			(size 1.3716 1.8796)
			(layers "F.Cu" "F.Mask" "F.Paste")
			(net "P12V")
		)
		(pad "2" smd rect
			(at 1.9685 0 180)
			(size 1.3716 1.8796)
			(layers "F.Cu" "F.Mask" "F.Paste")
			(net "VT235_VDDH")
		)
	)
)
